# S9S_MB_2U (Grand Teton) — schematic netlist excerpt (pin names and nets, part order shuffled) for the footprints in the layout excerpt that follows; sources: Cadence DE-HDL packaged netlist, KiCad conversion of 03242023_DA0F0TMBIJ0_F0T_Motherboard_J_brd_V01_OCP.brd

J15  SCONN288_ADR50017P130CC  SCONN288_ADR50017-P130CC IO  pkg DDR288S_1-1VXB  page 96
  VIN_BULK0  = P12V_S3_AUX_CPU0_NVDIMM
  RFU0  = TP_CHH_CPU0_DIMM1_FRU_0
  VIN_MGMT  = P3V3_AUX
  HSCL  = I3C_SPD_DDREFGH_CPU0_LVC1_SCL_6
  HSDA  = I3C_SPD_DDREFGH_CPU0_LVC1_SDA
  VSS0  = GND
  DQ0_A  = M_H_CPU0_SA_DQ<0>
  VSS1  = GND
  DQ1_A  = M_H_CPU0_SA_DQ<1>
  VSS2  = GND
  DQS0_A_T  = M_H_CPU0_SA_DQS_DP<0>
  DQS0_A_C  = M_H_CPU0_SA_DQS_DN<0>
  VSS3  = GND
  DQ4_A  = M_H_CPU0_SA_DQ<4>
  VSS4  = GND
  DQ5_A  = M_H_CPU0_SA_DQ<5>
  VSS5  = GND
  DQ8_A  = M_H_CPU0_SA_DQ<8>
  VSS6  = GND
  DQ9_A  = M_H_CPU0_SA_DQ<9>
  VSS7  = GND
  DQS1_A_T  = M_H_CPU0_SA_DQS_DP<1>
  DQS1_A_C  = M_H_CPU0_SA_DQS_DN<1>
  VSS8  = GND
  DQ12_A  = M_H_CPU0_SA_DQ<12>
  VSS9  = GND
  DQ13_A  = M_H_CPU0_SA_DQ<13>
  VSS10  = GND
  DQ16_A  = M_H_CPU0_SA_DQ<16>
  VSS11  = GND
  DQ17_A  = M_H_CPU0_SA_DQ<17>
  VSS12  = GND
  DQS2_A_T  = M_H_CPU0_SA_DQS_DP<2>
  DQS2_A_C  = M_H_CPU0_SA_DQS_DN<2>
  VSS13  = GND
  DQ20_A  = M_H_CPU0_SA_DQ<20>
  VSS14  = GND
  DQ21_A  = M_H_CPU0_SA_DQ<21>
  VSS15  = GND
  DQ24_A  = M_H_CPU0_SA_DQ<24>
  VSS16  = GND
  DQ25_A  = M_H_CPU0_SA_DQ<25>
  VSS17  = GND
  DQS3_A_T  = M_H_CPU0_SA_DQS_DP<3>
  DQS3_A_C  = M_H_CPU0_SA_DQS_DN<3>
  VSS18  = GND
  DQ28_A  = M_H_CPU0_SA_DQ<28>
  VSS19  = GND
  DQ29_A  = M_H_CPU0_SA_DQ<29>
  VSS20  = GND
  CB0_A  = M_H_CPU0_SA_CB<0>
  VSS21  = GND
  CB1_A  = M_H_CPU0_SA_CB<1>
  VSS22  = GND
  DQS4_A_T  = M_H_CPU0_SA_DQS_DP<4>
  DQS4_A_C  = M_H_CPU0_SA_DQS_DN<4>
  VSS23  = GND
  CB4_A  = M_H_CPU0_SA_CB<4>
  VSS24  = GND
  CB5_A  = M_H_CPU0_SA_CB<5>
  VSS25  = GND
  ALERT_N  = M_H_CPU0_ALERT_N
  VSS26  = GND
  CS0_A_N  = M_H_CPU0_SA_CS_N<0>
  VSS27  = GND
  CA0_A  = M_H_CPU0_SA_CA<0>
  VSS28  = GND
  CA2_A  = M_H_CPU0_SA_CA<2>
  VSS29  = GND
  CA4_A  = M_H_CPU0_SA_CA<4>
  VSS30  = GND
  CA6_A  = M_H_CPU0_SA_CA<6>
  VSS31  = GND
  PAR_A  = M_H_CPU0_SA_PAR
  VSS32  = GND
  CA0_B  = M_H_CPU0_SB_CA<0>
  VSS33  = GND
  CA2_B  = M_H_CPU0_SB_CA<2>
  VSS34  = GND
  CA4_B  = M_H_CPU0_SB_CA<4>
  VSS35  = GND
  CA6_B  = M_H_CPU0_SB_CA<6>
  VSS36  = GND
  CS0_B_N  = M_H_CPU0_SB_CS_N<0>
  VSS37  = GND
  \lbd||rsp_a_n\  = M_H_CPU0_SA_RSP<0>
  \lbs||rsp_b_n\  = M_H_CPU0_SB_RSP<0>
  VSS38  = GND
  CB4_B  = M_H_CPU0_SB_CB<4>
  VSS39  = GND
  CB5_B  = M_H_CPU0_SB_CB<5>
  VSS40  = GND
  \dqs9_b_t||tdqs9_b_t||dbi4_b_n\  = M_H_CPU0_SB_DQS_DP<9>
  \dqs9_b_c||tdqs9_b_c\  = M_H_CPU0_SB_DQS_DN<9>
  VSS41  = GND
  CB0_B  = M_H_CPU0_SB_CB<0>
  VSS42  = GND
  CB1_B  = M_H_CPU0_SB_CB<1>
  VSS43  = GND
  DQ0_B  = M_H_CPU0_SB_DQ<0>
  VSS44  = GND
  DQ1_B  = M_H_CPU0_SB_DQ<1>
  VSS45  = GND
  DQS0_B_T  = M_H_CPU0_SB_DQS_DP<0>
  DQS0_B_C  = M_H_CPU0_SB_DQS_DN<0>
  VSS46  = GND
  DQ4_B  = M_H_CPU0_SB_DQ<4>
  VSS47  = GND
  DQ5_B  = M_H_CPU0_SB_DQ<5>
  VSS48  = GND
  DQ8_B  = M_H_CPU0_SB_DQ<8>
  VSS49  = GND
  DQ9_B  = M_H_CPU0_SB_DQ<9>
  VSS50  = GND
  DQS1_B_T  = M_H_CPU0_SB_DQS_DP<1>
  DQS1_B_C  = M_H_CPU0_SB_DQS_DN<1>
  VSS51  = GND
  DQ12_B  = M_H_CPU0_SB_DQ<12>
  VSS52  = GND
  DQ13_B  = M_H_CPU0_SB_DQ<13>
  VSS53  = GND
  DQ16_B  = M_H_CPU0_SB_DQ<16>
  VSS54  = GND
  DQ17_B  = M_H_CPU0_SB_DQ<17>
  VSS55  = GND
  DQS2_B_T  = M_H_CPU0_SB_DQS_DP<2>
  DQS2_B_C  = M_H_CPU0_SB_DQS_DN<2>
  VSS56  = GND
  DQ20_B  = M_H_CPU0_SB_DQ<20>
  VSS57  = GND
  DQ21_B  = M_H_CPU0_SB_DQ<21>
  VSS58  = GND
  DQ24_B  = M_H_CPU0_SB_DQ<24>
  VSS59  = GND
  DQ25_B  = M_H_CPU0_SB_DQ<25>
  VSS60  = GND
  DQS3_B_T  = M_H_CPU0_SB_DQS_DP<3>
  DQS3_B_C  = M_H_CPU0_SB_DQS_DN<3>
  VSS61  = GND
  DQ28_B  = M_H_CPU0_SB_DQ<28>
  VSS62  = GND
  DQ29_B  = M_H_CPU0_SB_DQ<29>
  VSS63  = GND
  RFU1  = TP_CHH_CPU0_DIMM1_FRU_1
  VIN_BULK1  = P12V_S3_AUX_CPU0_NVDIMM
  VIN_BULK2  = P12V_S3_AUX_CPU0_NVDIMM
  \pwr_good||fail_n\  = PWRGD_CHH_CPU0_DIMM1
  HSA  = PD_CHH_CPU0_DIMM1_SAA
  RFU2  = TP_CHH_CPU0_DIMM1_FRU_2
  RFU3  = TP_CHH_CPU0_DIMM1_FRU_3
  VSS64  = GND
  DQ2_A  = M_H_CPU0_SA_DQ<2>
  VSS65  = GND
  DQ3_A  = M_H_CPU0_SA_DQ<3>
  VSS66  = GND
  \dqs5_a_c||tdqs5_a_c||dqs5_a_t||tdqs5_a_t\  = M_H_CPU0_SA_DQS_DN<5>
  \dqs5_a_t||tdqs5_a_t\  = M_H_CPU0_SA_DQS_DP<5>
  VSS67  = GND
  DQ6_A  = M_H_CPU0_SA_DQ<6>
  VSS68  = GND
  DQ7_A  = M_H_CPU0_SA_DQ<7>
  VSS69  = GND
  DQ10_A  = M_H_CPU0_SA_DQ<10>
  VSS70  = GND
  DQ11_A  = M_H_CPU0_SA_DQ<11>
  VSS71  = GND
  \dqs6_a_c||tdqs6_a_c||dqs6_a_t||tdqs6_a_t\  = M_H_CPU0_SA_DQS_DN<6>
  \dqs6_a_t||tdqs6_a_t\  = M_H_CPU0_SA_DQS_DP<6>
  VSS72  = GND
  DQ14_A  = M_H_CPU0_SA_DQ<14>
  VSS73  = GND
  DQ15_A  = M_H_CPU0_SA_DQ<15>
  VSS74  = GND
  DQ18_A  = M_H_CPU0_SA_DQ<18>
  VSS75  = GND
  DQ19_A  = M_H_CPU0_SA_DQ<19>
  VSS76  = GND
  \dqs7_a_c||tdqs7_a_c\  = M_H_CPU0_SA_DQS_DN<7>
  \dqs7_a_t||tdqs7_a_t\  = M_H_CPU0_SA_DQS_DP<7>
  VSS77  = GND
  DQ22_A  = M_H_CPU0_SA_DQ<22>
  VSS78  = GND
  DQ23_A  = M_H_CPU0_SA_DQ<23>
  VSS79  = GND
  DQ26_A  = M_H_CPU0_SA_DQ<26>
  VSS80  = GND
  DQ27_A  = M_H_CPU0_SA_DQ<27>
  VSS81  = GND
  \dqs8_a_c||tdqs8_a_c\  = M_H_CPU0_SA_DQS_DN<8>
  \dqs8_a_t||tdqs8_a_t\  = M_H_CPU0_SA_DQS_DP<8>
  VSS82  = GND
  DQ30_A  = M_H_CPU0_SA_DQ<30>
  VSS83  = GND
  DQ31_A  = M_H_CPU0_SA_DQ<31>
  VSS84  = GND
  CB2_A  = M_H_CPU0_SA_CB<2>
  VSS85  = GND
  CB3_A  = M_H_CPU0_SA_CB<3>
  VSS86  = GND
  \dqs9_a_c||tdqs9_a_c\  = M_H_CPU0_SA_DQS_DN<9>
  \dqs9_a_t||tdqs9_a_t\  = M_H_CPU0_SA_DQS_DP<9>
  VSS87  = GND
  CB6_A  = M_H_CPU0_SA_CB<6>
  VSS88  = GND
  CB7_A  = M_H_CPU0_SA_CB<7>
  VSS89  = GND
  RESET_N  = RST_M_GH_CPU0_FPGA_N
  VSS90  = GND
  CS1_A_N  = M_H_CPU0_SA_CS_N<1>
  VSS91  = GND
  CA1_A  = M_H_CPU0_SA_CA<1>
  VSS92  = GND
  CA3_A  = M_H_CPU0_SA_CA<3>
  VSS93  = GND
  CA5_A  = M_H_CPU0_SA_CA<5>
  VSS94  = GND
  CK_T  = M_H_CPU0_CLK_DP<0>
  CK_C  = M_H_CPU0_CLK_DN<0>
  VSS95  = GND
  RFU4  = TP_CHH_CPU0_DIMM1_FRU_4
  CA1_B  = M_H_CPU0_SB_CA<1>
  VSS96  = GND
  CA3_B  = M_H_CPU0_SB_CA<3>
  VSS97  = GND
  CA5_B  = M_H_CPU0_SB_CA<5>
  VSS98  = GND
  PAR_B  = M_H_CPU0_SB_PAR
  VSS99  = GND
  CS1_B_N  = M_H_CPU0_SB_CS_N<1>
  VSS100  = GND
  RFU5  = TP_CHH_CPU0_DIMM1_FRU_5
  RFU6  = TP_CHH_CPU0_DIMM1_FRU_6
  VSS101  = GND
  CB6_B  = M_H_CPU0_SB_CB<6>
  VSS102  = GND
  CB7_B  = M_H_CPU0_SB_CB<7>
  VSS103  = GND
  DQS4_B_C  = M_H_CPU0_SB_DQS_DN<4>
  DQS4_B_T  = M_H_CPU0_SB_DQS_DP<4>
  VSS104  = GND
  CB2_B  = M_H_CPU0_SB_CB<2>
  VSS105  = GND
  CB3_B  = M_H_CPU0_SB_CB<3>
  VSS106  = GND
  DQ2_B  = M_H_CPU0_SB_DQ<2>
  VSS107  = GND
  DQ3_B  = M_H_CPU0_SB_DQ<3>
  VSS108  = GND
  \dqs5_b_c||tdqs5_b_c\  = M_H_CPU0_SB_DQS_DN<5>
  \dqs5_b_t||tdqs5_b_t\  = M_H_CPU0_SB_DQS_DP<5>
  VSS109  = GND
  DQ6_B  = M_H_CPU0_SB_DQ<6>
  VSS110  = GND
  DQ7_B  = M_H_CPU0_SB_DQ<7>
  VSS111  = GND
  DQ10_B  = M_H_CPU0_SB_DQ<10>
  VSS112  = GND
  DQ11_B  = M_H_CPU0_SB_DQ<11>
  VSS113  = GND
  \dqs6_b_c||tdqs6_b_c\  = M_H_CPU0_SB_DQS_DN<6>
  \dqs6_b_t||tdqs6_b_t\  = M_H_CPU0_SB_DQS_DP<6>
  VSS114  = GND
  DQ14_B  = M_H_CPU0_SB_DQ<14>
  VSS115  = GND
  DQ15_B  = M_H_CPU0_SB_DQ<15>
  VSS116  = GND
  DQ18_B  = M_H_CPU0_SB_DQ<18>
  VSS117  = GND
  DQ19_B  = M_H_CPU0_SB_DQ<19>
  VSS118  = GND
  \dqs7_b_c||tdqs7_b_c\  = M_H_CPU0_SB_DQS_DN<7>
  \dqs7_b_t||tdqs7_b_t\  = M_H_CPU0_SB_DQS_DP<7>
  VSS119  = GND
  DQ22_B  = M_H_CPU0_SB_DQ<22>
  VSS120  = GND
  DQ23_B  = M_H_CPU0_SB_DQ<23>
  VSS121  = GND
  DQ26_B  = M_H_CPU0_SB_DQ<26>
  VSS122  = GND
  DQ27_B  = M_H_CPU0_SB_DQ<27>
  VSS123  = GND
  \dqs8_b_c||tdqs8_b_c\  = M_H_CPU0_SB_DQS_DN<8>
  \dqs8_b_t||tdqs8_b_t\  = M_H_CPU0_SB_DQS_DP<8>
  VSS124  = GND
  DQ30_B  = M_H_CPU0_SB_DQ<30>
  VSS125  = GND
  DQ31_B  = M_H_CPU0_SB_DQ<31>
  VSS126  = GND
  G1  = GND
  G2  = GND
  G3  = GND

(kicad_pcb
	(version 20260206)
	(generator "pcbnew")
	(generator_version "10.0")
	(general
		(thickness 1.6)
		(legacy_teardrops no)
	)
	(paper "A4")
	(title_block
		(title "03242023_DA0F0TMBIJ0_F0T_Motherboard_J_brd_V01_OCP.brd")
		(comment 1 "Grand Teton / footprint 2194 of 6105 (J15), pads 183-228 of 291")
	)
	(layers
		(0 "F.Cu" signal "TOP")
		(4 "In1.Cu" signal "GND")
		(6 "In2.Cu" signal "IN1")
		(8 "In3.Cu" signal "GND1")
		(10 "In4.Cu" signal "IN2")
		(12 "In5.Cu" signal "GND2")
		(14 "In6.Cu" signal "IN3")
		(16 "In7.Cu" signal "GND3")
		(18 "In8.Cu" signal "VCC")
		(20 "In9.Cu" signal "VCC1")
		(22 "In10.Cu" signal "GND4")
		(24 "In11.Cu" signal "IN4")
		(26 "In12.Cu" signal "GND5")
		(28 "In13.Cu" signal "IN5")
		(30 "In14.Cu" signal "GND6")
		(32 "In15.Cu" signal "IN6")
		(34 "In16.Cu" signal "GND7")
		(2 "B.Cu" signal "BOTTOM")
		(9 "F.Adhes" user "F.Adhesive")
		(11 "B.Adhes" user "B.Adhesive")
		(13 "F.Paste" user "Package Geometry/Pastemask Top")
		(15 "B.Paste" user "Package Geometry/Pastemask Bottom")
		(5 "F.SilkS" user "Ref Des/Silkscreen Top")
		(7 "B.SilkS" user "Ref Des/Silkscreen Bottom")
		(1 "F.Mask" user "Board Geometry/Soldermask Top")
		(3 "B.Mask" user "Board Geometry/Soldermask Bottom")
		(17 "Dwgs.User" user "User.Drawings")
		(19 "Cmts.User" user "User.Comments")
		(21 "Eco1.User" user "User.Eco1")
		(23 "Eco2.User" user "User.Eco2")
		(25 "Edge.Cuts" user "Board Geometry/Outline")
		(27 "Margin" user)
		(31 "F.CrtYd" user "Package Geometry/Place Bound Top")
		(29 "B.CrtYd" user "Package Geometry/Place Bound Bottom")
		(35 "F.Fab" user "Ref Des/Assembly Top")
		(33 "B.Fab" user "Ref Des/Assembly Bottom")
	)
	(footprint ""
		(layer "F.Cu")
		(at 461.609948 -258.091686)
		(property "Reference" "J15"
			(at 3.019552 -81.652872 0)
			(unlocked yes)
			(layer "F.SilkS")
			(effects
				(font
					(size 0.7874 0.5842)
					(thickness 0.1524)
				)
				(justify left)
			)
		)
		(property "Value" ""
			(at 0 0 0)
			(layer "F.Fab")
			(effects
				(font
					(size 1.27 1.27)
				)
			)
		)
		(duplicate_pad_numbers_are_jumpers no)
		(pad "183" smd rect
			(at 2.050034 -31.025084 270)
			(size 0.519938 1.4986)
			(layers "F.Cu" "F.Mask" "F.Paste")
			(net "M_H_CPU0_SA_DQ<23>")
		)
		(pad "184" smd rect
			(at 2.050034 -30.174946 270)
			(size 0.519938 1.4986)
			(layers "F.Cu" "F.Mask" "F.Paste")
			(net "GND")
		)
		(pad "185" smd rect
			(at 2.050034 -29.325062 270)
			(size 0.519938 1.4986)
			(layers "F.Cu" "F.Mask" "F.Paste")
			(net "M_H_CPU0_SA_DQ<26>")
		)
		(pad "186" smd rect
			(at 2.050034 -28.474924 270)
			(size 0.519938 1.4986)
			(layers "F.Cu" "F.Mask" "F.Paste")
			(net "GND")
		)
		(pad "187" smd rect
			(at 2.050034 -27.62504 270)
			(size 0.519938 1.4986)
			(layers "F.Cu" "F.Mask" "F.Paste")
			(net "M_H_CPU0_SA_DQ<27>")
		)
		(pad "188" smd rect
			(at 2.050034 -26.774902 270)
			(size 0.519938 1.4986)
			(layers "F.Cu" "F.Mask" "F.Paste")
			(net "GND")
		)
		(pad "189" smd rect
			(at 2.050034 -25.925018 270)
			(size 0.519938 1.4986)
			(layers "F.Cu" "F.Mask" "F.Paste")
			(net "M_H_CPU0_SA_DQS_DN<8>")
		)
		(pad "190" smd rect
			(at 2.050034 -25.07488 270)
			(size 0.519938 1.4986)
			(layers "F.Cu" "F.Mask" "F.Paste")
			(net "M_H_CPU0_SA_DQS_DP<8>")
		)
		(pad "191" smd rect
			(at 2.050034 -24.224996 270)
			(size 0.519938 1.4986)
			(layers "F.Cu" "F.Mask" "F.Paste")
			(net "GND")
		)
		(pad "192" smd rect
			(at 2.050034 -23.375112 270)
			(size 0.519938 1.4986)
			(layers "F.Cu" "F.Mask" "F.Paste")
			(net "M_H_CPU0_SA_DQ<30>")
		)
		(pad "193" smd rect
			(at 2.050034 -22.524974 270)
			(size 0.519938 1.4986)
			(layers "F.Cu" "F.Mask" "F.Paste")
			(net "GND")
		)
		(pad "194" smd rect
			(at 2.050034 -21.67509 270)
			(size 0.519938 1.4986)
			(layers "F.Cu" "F.Mask" "F.Paste")
			(net "M_H_CPU0_SA_DQ<31>")
		)
		(pad "195" smd rect
			(at 2.050034 -20.824952 270)
			(size 0.519938 1.4986)
			(layers "F.Cu" "F.Mask" "F.Paste")
			(net "GND")
		)
		(pad "196" smd rect
			(at 2.050034 -19.975068 270)
			(size 0.519938 1.4986)
			(layers "F.Cu" "F.Mask" "F.Paste")
			(net "M_H_CPU0_SA_CB<2>")
		)
		(pad "197" smd rect
			(at 2.050034 -19.12493 270)
			(size 0.519938 1.4986)
			(layers "F.Cu" "F.Mask" "F.Paste")
			(net "GND")
		)
		(pad "198" smd rect
			(at 2.050034 -18.275046 270)
			(size 0.519938 1.4986)
			(layers "F.Cu" "F.Mask" "F.Paste")
			(net "M_H_CPU0_SA_CB<3>")
		)
		(pad "199" smd rect
			(at 2.050034 -17.424908 270)
			(size 0.519938 1.4986)
			(layers "F.Cu" "F.Mask" "F.Paste")
			(net "GND")
		)
		(pad "200" smd rect
			(at 2.050034 -16.575024 270)
			(size 0.519938 1.4986)
			(layers "F.Cu" "F.Mask" "F.Paste")
			(net "M_H_CPU0_SA_DQS_DN<9>")
		)
		(pad "201" smd rect
			(at 2.050034 -15.724886 270)
			(size 0.519938 1.4986)
			(layers "F.Cu" "F.Mask" "F.Paste")
			(net "M_H_CPU0_SA_DQS_DP<9>")
		)
		(pad "202" smd rect
			(at 2.050034 -14.875002 270)
			(size 0.519938 1.4986)
			(layers "F.Cu" "F.Mask" "F.Paste")
			(net "GND")
		)
		(pad "203" smd rect
			(at 2.050034 -14.025118 270)
			(size 0.519938 1.4986)
			(layers "F.Cu" "F.Mask" "F.Paste")
			(net "M_H_CPU0_SA_CB<6>")
		)
		(pad "204" smd rect
			(at 2.050034 -13.17498 270)
			(size 0.519938 1.4986)
			(layers "F.Cu" "F.Mask" "F.Paste")
			(net "GND")
		)
		(pad "205" smd rect
			(at 2.050034 -12.325096 270)
			(size 0.519938 1.4986)
			(layers "F.Cu" "F.Mask" "F.Paste")
			(net "M_H_CPU0_SA_CB<7>")
		)
		(pad "206" smd rect
			(at 2.050034 -11.474958 270)
			(size 0.519938 1.4986)
			(layers "F.Cu" "F.Mask" "F.Paste")
			(net "GND")
		)
		(pad "207" smd rect
			(at 2.050034 -10.625074 270)
			(size 0.519938 1.4986)
			(layers "F.Cu" "F.Mask" "F.Paste")
			(net "RST_M_GH_CPU0_FPGA_N")
		)
		(pad "208" smd rect
			(at 2.050034 -9.774936 270)
			(size 0.519938 1.4986)
			(layers "F.Cu" "F.Mask" "F.Paste")
			(net "GND")
		)
		(pad "209" smd rect
			(at 2.050034 -8.925052 270)
			(size 0.519938 1.4986)
			(layers "F.Cu" "F.Mask" "F.Paste")
			(net "M_H_CPU0_SA_CS_N<1>")
		)
		(pad "210" smd rect
			(at 2.050034 -8.074914 270)
			(size 0.519938 1.4986)
			(layers "F.Cu" "F.Mask" "F.Paste")
			(net "GND")
		)
		(pad "211" smd rect
			(at 2.050034 -7.22503 270)
			(size 0.519938 1.4986)
			(layers "F.Cu" "F.Mask" "F.Paste")
			(net "M_H_CPU0_SA_CA<1>")
		)
		(pad "212" smd rect
			(at 2.050034 -6.374892 270)
			(size 0.519938 1.4986)
			(layers "F.Cu" "F.Mask" "F.Paste")
			(net "GND")
		)
		(pad "213" smd rect
			(at 2.050034 -5.525008 270)
			(size 0.519938 1.4986)
			(layers "F.Cu" "F.Mask" "F.Paste")
			(net "M_H_CPU0_SA_CA<3>")
		)
		(pad "214" smd rect
			(at 2.050034 -4.675124 270)
			(size 0.519938 1.4986)
			(layers "F.Cu" "F.Mask" "F.Paste")
			(net "GND")
		)
		(pad "215" smd rect
			(at 2.050034 -3.824986 270)
			(size 0.519938 1.4986)
			(layers "F.Cu" "F.Mask" "F.Paste")
			(net "M_H_CPU0_SA_CA<5>")
		)
		(pad "216" smd rect
			(at 2.050034 -2.975102 270)
			(size 0.519938 1.4986)
			(layers "F.Cu" "F.Mask" "F.Paste")
			(net "GND")
		)
		(pad "217" smd rect
			(at 2.050034 -2.124964 270)
			(size 0.519938 1.4986)
			(layers "F.Cu" "F.Mask" "F.Paste")
			(net "M_H_CPU0_CLK_DP<0>")
		)
		(pad "218" smd rect
			(at 2.050034 -1.27508 270)
			(size 0.519938 1.4986)
			(layers "F.Cu" "F.Mask" "F.Paste")
			(net "M_H_CPU0_CLK_DN<0>")
		)
		(pad "219" smd rect
			(at 2.050034 -0.424942 270)
			(size 0.519938 1.4986)
			(layers "F.Cu" "F.Mask" "F.Paste")
			(net "GND")
		)
		(pad "220" smd rect
			(at 2.050034 5.525008 270)
			(size 0.519938 1.4986)
			(layers "F.Cu" "F.Mask" "F.Paste")
			(net "TP_CHH_CPU0_DIMM1_FRU_4")
		)
		(pad "221" smd rect
			(at 2.050034 6.374892 270)
			(size 0.519938 1.4986)
			(layers "F.Cu" "F.Mask" "F.Paste")
			(net "M_H_CPU0_SB_CA<1>")
		)
		(pad "222" smd rect
			(at 2.050034 7.22503 270)
			(size 0.519938 1.4986)
			(layers "F.Cu" "F.Mask" "F.Paste")
			(net "GND")
		)
		(pad "223" smd rect
			(at 2.050034 8.074914 270)
			(size 0.519938 1.4986)
			(layers "F.Cu" "F.Mask" "F.Paste")
			(net "M_H_CPU0_SB_CA<3>")
		)
		(pad "224" smd rect
			(at 2.050034 8.925052 270)
			(size 0.519938 1.4986)
			(layers "F.Cu" "F.Mask" "F.Paste")
			(net "GND")
		)
		(pad "225" smd rect
			(at 2.050034 9.774936 270)
			(size 0.519938 1.4986)
			(layers "F.Cu" "F.Mask" "F.Paste")
			(net "M_H_CPU0_SB_CA<5>")
		)
		(pad "226" smd rect
			(at 2.050034 10.625074 270)
			(size 0.519938 1.4986)
			(layers "F.Cu" "F.Mask" "F.Paste")
			(net "GND")
		)
		(pad "227" smd rect
			(at 2.050034 11.474958 270)
			(size 0.519938 1.4986)
			(layers "F.Cu" "F.Mask" "F.Paste")
			(net "M_H_CPU0_SB_PAR")
		)
		(pad "228" smd rect
			(at 2.050034 12.325096 270)
			(size 0.519938 1.4986)
			(layers "F.Cu" "F.Mask" "F.Paste")
			(net "GND")
		)
	)
)
